(kicad_pcb
	(version 20260206)
	(generator "pcbnew")
	(generator_version "10.0")
	(general
		(thickness 1.6)
		(legacy_teardrops no)
	)
	(paper "A4")
	(title_block
		(title "12092022_DA0F0TMDCD0_F0T_Management_Board_D_brd_V3_OCP.brd")
		(comment 1 "Grand Teton / footprints 588-593 of 1440")
	)
	(layers
		(0 "F.Cu" signal "TOP")
		(4 "In1.Cu" signal "GND")
		(6 "In2.Cu" signal "IN1")
		(8 "In3.Cu" signal "GND1")
		(10 "In4.Cu" signal "IN2")
		(12 "In5.Cu" signal "VCC")
		(14 "In6.Cu" signal "VCC1")
		(16 "In7.Cu" signal "IN3")
		(18 "In8.Cu" signal "GND2")
		(20 "In9.Cu" signal "IN4")
		(22 "In10.Cu" signal "GND3")
		(2 "B.Cu" signal "BOTTOM")
		(9 "F.Adhes" user "F.Adhesive")
		(11 "B.Adhes" user "B.Adhesive")
		(13 "F.Paste" user "Package Geometry/Pastemask Top")
		(15 "B.Paste" user "Package Geometry/Pastemask Bottom")
		(5 "F.SilkS" user "Ref Des/Silkscreen Top")
		(7 "B.SilkS" user "Ref Des/Silkscreen Bottom")
		(1 "F.Mask" user "Board Geometry/Soldermask Top")
		(3 "B.Mask" user "Board Geometry/Soldermask Bottom")
		(17 "Dwgs.User" user "User.Drawings")
		(19 "Cmts.User" user "User.Comments")
		(21 "Eco1.User" user "User.Eco1")
		(23 "Eco2.User" user "User.Eco2")
		(25 "Edge.Cuts" user "Board Geometry/Outline")
		(27 "Margin" user)
		(31 "F.CrtYd" user "Package Geometry/Place Bound Top")
		(29 "B.CrtYd" user "Package Geometry/Place Bound Bottom")
		(35 "F.Fab" user "Ref Des/Assembly Top")
		(33 "B.Fab" user "Ref Des/Assembly Bottom")
	)
	(footprint ""
		(layer "F.Cu")
		(at 30.967172 -83.816952 -90)
		(property "Reference" "R663"
			(at 0 0 270)
			(layer "F.SilkS")
			(hide yes)
			(effects
				(font
					(size 1.27 1.27)
				)
			)
		)
		(property "Value" ""
			(at 0 0 270)
			(layer "F.Fab")
			(effects
				(font
					(size 1.27 1.27)
				)
			)
		)
		(duplicate_pad_numbers_are_jumpers no)
		(fp_line
			(start -0.7874 0.4064)
			(end -0.7874 -0.4064)
			(stroke
				(width 0.1524)
				(type default)
			)
			(layer "F.SilkS")
		)
		(fp_line
			(start 0.7874 0.4064)
			(end -0.7874 0.4064)
			(stroke
				(width 0.1524)
				(type default)
			)
			(layer "F.SilkS")
		)
		(fp_line
			(start -0.7874 -0.4064)
			(end 0.7874 -0.4064)
			(stroke
				(width 0.1524)
				(type default)
			)
			(layer "F.SilkS")
		)
		(fp_line
			(start 0.7874 -0.4064)
			(end 0.7874 0.4064)
			(stroke
				(width 0.1524)
				(type default)
			)
			(layer "F.SilkS")
		)
		(fp_line
			(start -0.67945 0.3048)
			(end -0.67945 -0.305054)
			(stroke
				(width 0.1)
				(type default)
			)
			(layer "F.Fab")
		)
		(fp_line
			(start -0.12065 0.3048)
			(end -0.67945 0.3048)
			(stroke
				(width 0.1)
				(type default)
			)
			(layer "F.Fab")
		)
		(fp_line
			(start 0.120396 0.3048)
			(end 0.120396 0.2794)
			(stroke
				(width 0.1)
				(type default)
			)
			(layer "F.Fab")
		)
		(fp_line
			(start 0.67945 0.3048)
			(end 0.120396 0.3048)
			(stroke
				(width 0.1)
				(type default)
			)
			(layer "F.Fab")
		)
		(fp_line
			(start -0.12065 0.2794)
			(end -0.12065 0.3048)
			(stroke
				(width 0.1)
				(type default)
			)
			(layer "F.Fab")
		)
		(fp_line
			(start 0.120396 0.2794)
			(end -0.12065 0.2794)
			(stroke
				(width 0.1)
				(type default)
			)
			(layer "F.Fab")
		)
		(fp_line
			(start -0.12065 -0.2794)
			(end 0.12065 -0.2794)
			(stroke
				(width 0.1)
				(type default)
			)
			(layer "F.Fab")
		)
		(fp_line
			(start 0.12065 -0.2794)
			(end 0.12065 -0.3048)
			(stroke
				(width 0.1)
				(type default)
			)
			(layer "F.Fab")
		)
		(fp_line
			(start 0.12065 -0.3048)
			(end 0.67945 -0.3048)
			(stroke
				(width 0.1)
				(type default)
			)
			(layer "F.Fab")
		)
		(fp_line
			(start 0.67945 -0.3048)
			(end 0.67945 0.3048)
			(stroke
				(width 0.1)
				(type default)
			)
			(layer "F.Fab")
		)
		(fp_line
			(start -0.67945 -0.305054)
			(end -0.12065 -0.305054)
			(stroke
				(width 0.1)
				(type default)
			)
			(layer "F.Fab")
		)
		(fp_line
			(start -0.12065 -0.305054)
			(end -0.12065 -0.2794)
			(stroke
				(width 0.1)
				(type default)
			)
			(layer "F.Fab")
		)
		(pad "1" smd circle
			(at -0.40005 0 270)
			(size 0 0)
			(layers "F.Cu" "F.Mask" "F.Paste")
			(net "P3V3_AUX")
		)
		(pad "2" smd circle
			(at 0.40005 0 270)
			(size 0 0)
			(layers "F.Cu" "F.Mask" "F.Paste")
			(net "EMMC_CMD_R")
		)
	)
	(footprint ""
		(layer "F.Cu")
		(at 19.3421 -37.868352 180)
		(property "Reference" "PC262"
			(at 0 0 180)
			(layer "F.SilkS")
			(hide yes)
			(effects
				(font
					(size 1.27 1.27)
				)
			)
		)
		(property "Value" ""
			(at 0 0 180)
			(layer "F.Fab")
			(effects
				(font
					(size 1.27 1.27)
				)
			)
		)
		(duplicate_pad_numbers_are_jumpers no)
		(fp_line
			(start 1.651 0.8382)
			(end -1.651 0.8382)
			(stroke
				(width 0.1524)
				(type default)
			)
			(layer "F.SilkS")
		)
		(fp_line
			(start 1.651 -0.8382)
			(end 1.651 0.8382)
			(stroke
				(width 0.1524)
				(type default)
			)
			(layer "F.SilkS")
		)
		(fp_line
			(start 0 0.8382)
			(end 0 -0.8382)
			(stroke
				(width 0.1524)
				(type default)
			)
			(layer "F.SilkS")
		)
		(fp_line
			(start -1.651 0.8382)
			(end -1.651 -0.8382)
			(stroke
				(width 0.1524)
				(type default)
			)
			(layer "F.SilkS")
		)
		(fp_line
			(start -1.651 -0.8382)
			(end 1.651 -0.8382)
			(stroke
				(width 0.1524)
				(type default)
			)
			(layer "F.SilkS")
		)
		(fp_line
			(start 1.55956 0.7366)
			(end 1.55956 -0.7366)
			(stroke
				(width 0.1)
				(type default)
			)
			(layer "F.Fab")
		)
		(fp_line
			(start 1.55956 -0.7366)
			(end 1.524 -0.7366)
			(stroke
				(width 0.1)
				(type default)
			)
			(layer "F.Fab")
		)
		(fp_line
			(start 1.524 0.7366)
			(end 1.55956 0.7366)
			(stroke
				(width 0.1)
				(type default)
			)
			(layer "F.Fab")
		)
		(fp_line
			(start 1.524 -0.7366)
			(end -1.524 -0.7366)
			(stroke
				(width 0.1)
				(type default)
			)
			(layer "F.Fab")
		)
		(fp_line
			(start -1.524 0.7366)
			(end 1.524 0.7366)
			(stroke
				(width 0.1)
				(type default)
			)
			(layer "F.Fab")
		)
		(fp_line
			(start -1.524 -0.7366)
			(end -1.55956 -0.7366)
			(stroke
				(width 0.1)
				(type default)
			)
			(layer "F.Fab")
		)
		(fp_line
			(start -1.55956 0.7366)
			(end -1.524 0.7366)
			(stroke
				(width 0.1)
				(type default)
			)
			(layer "F.Fab")
		)
		(fp_line
			(start -1.55956 -0.7366)
			(end -1.55956 0.7366)
			(stroke
				(width 0.1)
				(type default)
			)
			(layer "F.Fab")
		)
		(pad "1" smd rect
			(at -0.94996 0)
			(size 1.1176 1.3716)
			(layers "F.Cu" "F.Mask" "F.Paste")
			(net "SW_P1V0_AUX_FLT")
		)
		(pad "2" smd rect
			(at 0.94996 0)
			(size 1.1176 1.3716)
			(layers "F.Cu" "F.Mask" "F.Paste")
			(net "GND")
		)
	)
	(footprint ""
		(layer "F.Cu")
		(at 25.781 -65.913 -90)
		(property "Reference" "R39"
			(at 0 0 270)
			(layer "F.SilkS")
			(hide yes)
			(effects
				(font
					(size 1.27 1.27)
				)
			)
		)
		(property "Value" ""
			(at 0 0 270)
			(layer "F.Fab")
			(effects
				(font
					(size 1.27 1.27)
				)
			)
		)
		(duplicate_pad_numbers_are_jumpers no)
		(fp_line
			(start -0.7874 0.4064)
			(end -0.7874 -0.4064)
			(stroke
				(width 0.1524)
				(type default)
			)
			(layer "F.SilkS")
		)
		(fp_line
			(start 0.7874 0.4064)
			(end -0.7874 0.4064)
			(stroke
				(width 0.1524)
				(type default)
			)
			(layer "F.SilkS")
		)
		(fp_line
			(start -0.7874 -0.4064)
			(end 0.7874 -0.4064)
			(stroke
				(width 0.1524)
				(type default)
			)
			(layer "F.SilkS")
		)
		(fp_line
			(start 0.7874 -0.4064)
			(end 0.7874 0.4064)
			(stroke
				(width 0.1524)
				(type default)
			)
			(layer "F.SilkS")
		)
		(fp_line
			(start -0.67945 0.3048)
			(end -0.67945 -0.305054)
			(stroke
				(width 0.1)
				(type default)
			)
			(layer "F.Fab")
		)
		(fp_line
			(start -0.12065 0.3048)
			(end -0.67945 0.3048)
			(stroke
				(width 0.1)
				(type default)
			)
			(layer "F.Fab")
		)
		(fp_line
			(start 0.120396 0.3048)
			(end 0.120396 0.2794)
			(stroke
				(width 0.1)
				(type default)
			)
			(layer "F.Fab")
		)
		(fp_line
			(start 0.67945 0.3048)
			(end 0.120396 0.3048)
			(stroke
				(width 0.1)
				(type default)
			)
			(layer "F.Fab")
		)
		(fp_line
			(start -0.12065 0.2794)
			(end -0.12065 0.3048)
			(stroke
				(width 0.1)
				(type default)
			)
			(layer "F.Fab")
		)
		(fp_line
			(start 0.120396 0.2794)
			(end -0.12065 0.2794)
			(stroke
				(width 0.1)
				(type default)
			)
			(layer "F.Fab")
		)
		(fp_line
			(start -0.12065 -0.2794)
			(end 0.12065 -0.2794)
			(stroke
				(width 0.1)
				(type default)
			)
			(layer "F.Fab")
		)
		(fp_line
			(start 0.12065 -0.2794)
			(end 0.12065 -0.3048)
			(stroke
				(width 0.1)
				(type default)
			)
			(layer "F.Fab")
		)
		(fp_line
			(start 0.12065 -0.3048)
			(end 0.67945 -0.3048)
			(stroke
				(width 0.1)
				(type default)
			)
			(layer "F.Fab")
		)
		(fp_line
			(start 0.67945 -0.3048)
			(end 0.67945 0.3048)
			(stroke
				(width 0.1)
				(type default)
			)
			(layer "F.Fab")
		)
		(fp_line
			(start -0.67945 -0.305054)
			(end -0.12065 -0.305054)
			(stroke
				(width 0.1)
				(type default)
			)
			(layer "F.Fab")
		)
		(fp_line
			(start -0.12065 -0.305054)
			(end -0.12065 -0.2794)
			(stroke
				(width 0.1)
				(type default)
			)
			(layer "F.Fab")
		)
		(pad "1" smd circle
			(at -0.40005 0 270)
			(size 0 0)
			(layers "F.Cu" "F.Mask" "F.Paste")
			(net "SPA_SOUT_SW_BUF_R")
		)
		(pad "2" smd circle
			(at 0.40005 0 270)
			(size 0 0)
			(layers "F.Cu" "F.Mask" "F.Paste")
			(net "SPA_SOUT_SW_BUF")
		)
	)
	(footprint ""
		(layer "F.Cu")
		(at 41.8592 -28.6512 180)
		(property "Reference" "C180"
			(at 0 0 180)
			(layer "F.SilkS")
			(hide yes)
			(effects
				(font
					(size 1.27 1.27)
				)
			)
		)
		(property "Value" ""
			(at 0 0 180)
			(layer "F.Fab")
			(effects
				(font
					(size 1.27 1.27)
				)
			)
		)
		(duplicate_pad_numbers_are_jumpers no)
		(fp_line
			(start 0.7874 0.4064)
			(end -0.7874 0.4064)
			(stroke
				(width 0.1524)
				(type default)
			)
			(layer "F.SilkS")
		)
		(fp_line
			(start 0.7874 -0.4064)
			(end 0.7874 0.4064)
			(stroke
				(width 0.1524)
				(type default)
			)
			(layer "F.SilkS")
		)
		(fp_line
			(start -0.7874 0.4064)
			(end -0.7874 -0.4064)
			(stroke
				(width 0.1524)
				(type default)
			)
			(layer "F.SilkS")
		)
		(fp_line
			(start -0.7874 -0.4064)
			(end 0.7874 -0.4064)
			(stroke
				(width 0.1524)
				(type default)
			)
			(layer "F.SilkS")
		)
		(fp_line
			(start 0.67945 0.3048)
			(end 0.120396 0.3048)
			(stroke
				(width 0.1)
				(type default)
			)
			(layer "F.Fab")
		)
		(fp_line
			(start 0.67945 -0.3048)
			(end 0.67945 0.3048)
			(stroke
				(width 0.1)
				(type default)
			)
			(layer "F.Fab")
		)
		(fp_line
			(start 0.12065 -0.2794)
			(end 0.12065 -0.3048)
			(stroke
				(width 0.1)
				(type default)
			)
			(layer "F.Fab")
		)
		(fp_line
			(start 0.12065 -0.3048)
			(end 0.67945 -0.3048)
			(stroke
				(width 0.1)
				(type default)
			)
			(layer "F.Fab")
		)
		(fp_line
			(start 0.120396 0.3048)
			(end 0.120396 0.2794)
			(stroke
				(width 0.1)
				(type default)
			)
			(layer "F.Fab")
		)
		(fp_line
			(start 0.120396 0.2794)
			(end -0.12065 0.2794)
			(stroke
				(width 0.1)
				(type default)
			)
			(layer "F.Fab")
		)
		(fp_line
			(start -0.12065 0.3048)
			(end -0.67945 0.3048)
			(stroke
				(width 0.1)
				(type default)
			)
			(layer "F.Fab")
		)
		(fp_line
			(start -0.12065 0.2794)
			(end -0.12065 0.3048)
			(stroke
				(width 0.1)
				(type default)
			)
			(layer "F.Fab")
		)
		(fp_line
			(start -0.12065 -0.2794)
			(end 0.12065 -0.2794)
			(stroke
				(width 0.1)
				(type default)
			)
			(layer "F.Fab")
		)
		(fp_line
			(start -0.12065 -0.305054)
			(end -0.12065 -0.2794)
			(stroke
				(width 0.1)
				(type default)
			)
			(layer "F.Fab")
		)
		(fp_line
			(start -0.67945 0.3048)
			(end -0.67945 -0.305054)
			(stroke
				(width 0.1)
				(type default)
			)
			(layer "F.Fab")
		)
		(fp_line
			(start -0.67945 -0.305054)
			(end -0.12065 -0.305054)
			(stroke
				(width 0.1)
				(type default)
			)
			(layer "F.Fab")
		)
		(pad "1" smd circle
			(at -0.40005 0 180)
			(size 0 0)
			(layers "F.Cu" "F.Mask" "F.Paste")
			(net "P3V3_LDO")
		)
		(pad "2" smd circle
			(at 0.40005 0 180)
			(size 0 0)
			(layers "F.Cu" "F.Mask" "F.Paste")
			(net "GND")
		)
	)
	(footprint ""
		(layer "F.Cu")
		(at 41.572942 -22.15642 -90)
		(property "Reference" "R666"
			(at 0 0 270)
			(layer "F.SilkS")
			(hide yes)
			(effects
				(font
					(size 1.27 1.27)
				)
			)
		)
		(property "Value" ""
			(at 0 0 270)
			(layer "F.Fab")
			(effects
				(font
					(size 1.27 1.27)
				)
			)
		)
		(duplicate_pad_numbers_are_jumpers no)
		(fp_line
			(start 0.7874 0.4064)
			(end -0.7874 0.4064)
			(stroke
				(width 0.1524)
				(type default)
			)
			(layer "F.SilkS")
		)
		(fp_line
			(start -0.7874 -0.4064)
			(end 0.7874 -0.4064)
			(stroke
				(width 0.1524)
				(type default)
			)
			(layer "F.SilkS")
		)
		(fp_line
			(start -0.67945 0.3048)
			(end -0.67945 -0.305054)
			(stroke
				(width 0.1)
				(type default)
			)
			(layer "F.Fab")
		)
		(fp_line
			(start -0.12065 0.3048)
			(end -0.67945 0.3048)
			(stroke
				(width 0.1)
				(type default)
			)
			(layer "F.Fab")
		)
		(fp_line
			(start 0.120396 0.3048)
			(end 0.120396 0.2794)
			(stroke
				(width 0.1)
				(type default)
			)
			(layer "F.Fab")
		)
		(fp_line
			(start 0.67945 0.3048)
			(end 0.120396 0.3048)
			(stroke
				(width 0.1)
				(type default)
			)
			(layer "F.Fab")
		)
		(fp_line
			(start -0.12065 0.2794)
			(end -0.12065 0.3048)
			(stroke
				(width 0.1)
				(type default)
			)
			(layer "F.Fab")
		)
		(fp_line
			(start 0.120396 0.2794)
			(end -0.12065 0.2794)
			(stroke
				(width 0.1)
				(type default)
			)
			(layer "F.Fab")
		)
		(fp_line
			(start -0.12065 -0.2794)
			(end 0.12065 -0.2794)
			(stroke
				(width 0.1)
				(type default)
			)
			(layer "F.Fab")
		)
		(fp_line
			(start 0.12065 -0.2794)
			(end 0.12065 -0.3048)
			(stroke
				(width 0.1)
				(type default)
			)
			(layer "F.Fab")
		)
		(fp_line
			(start 0.12065 -0.3048)
			(end 0.67945 -0.3048)
			(stroke
				(width 0.1)
				(type default)
			)
			(layer "F.Fab")
		)
		(fp_line
			(start 0.67945 -0.3048)
			(end 0.67945 0.3048)
			(stroke
				(width 0.1)
				(type default)
			)
			(layer "F.Fab")
		)
		(fp_line
			(start -0.67945 -0.305054)
			(end -0.12065 -0.305054)
			(stroke
				(width 0.1)
				(type default)
			)
			(layer "F.Fab")
		)
		(fp_line
			(start -0.12065 -0.305054)
			(end -0.12065 -0.2794)
			(stroke
				(width 0.1)
				(type default)
			)
			(layer "F.Fab")
		)
		(pad "1" smd circle
			(at -0.40005 0 270)
			(size 0 0)
			(layers "F.Cu" "F.Mask" "F.Paste")
			(net "USB3_01_MUX_FB_TXN")
		)
		(pad "2" smd circle
			(at 0.40005 0 270)
			(size 0 0)
			(layers "F.Cu" "F.Mask" "F.Paste")
			(net "USB3_01_FB_TXN")
		)
	)
	(footprint ""
		(layer "F.Cu")
		(at 39.50462 -30.63748 90)
		(property "Reference" "R213"
			(at 0 0 90)
			(layer "F.SilkS")
			(hide yes)
			(effects
				(font
					(size 1.27 1.27)
				)
			)
		)
		(property "Value" ""
			(at 0 0 90)
			(layer "F.Fab")
			(effects
				(font
					(size 1.27 1.27)
				)
			)
		)
		(duplicate_pad_numbers_are_jumpers no)
		(fp_line
			(start 0.7874 -0.4064)
			(end 0.7874 0.4064)
			(stroke
				(width 0.1524)
				(type default)
			)
			(layer "F.SilkS")
		)
		(fp_line
			(start -0.7874 -0.4064)
			(end 0.7874 -0.4064)
			(stroke
				(width 0.1524)
				(type default)
			)
			(layer "F.SilkS")
		)
		(fp_line
			(start 0.7874 0.4064)
			(end -0.7874 0.4064)
			(stroke
				(width 0.1524)
				(type default)
			)
			(layer "F.SilkS")
		)
		(fp_line
			(start -0.7874 0.4064)
			(end -0.7874 -0.4064)
			(stroke
				(width 0.1524)
				(type default)
			)
			(layer "F.SilkS")
		)
		(fp_line
			(start -0.12065 -0.305054)
			(end -0.12065 -0.2794)
			(stroke
				(width 0.1)
				(type default)
			)
			(layer "F.Fab")
		)
		(fp_line
			(start -0.67945 -0.305054)
			(end -0.12065 -0.305054)
			(stroke
				(width 0.1)
				(type default)
			)
			(layer "F.Fab")
		)
		(fp_line
			(start 0.67945 -0.3048)
			(end 0.67945 0.3048)
			(stroke
				(width 0.1)
				(type default)
			)
			(layer "F.Fab")
		)
		(fp_line
			(start 0.12065 -0.3048)
			(end 0.67945 -0.3048)
			(stroke
				(width 0.1)
				(type default)
			)
			(layer "F.Fab")
		)
		(fp_line
			(start 0.12065 -0.2794)
			(end 0.12065 -0.3048)
			(stroke
				(width 0.1)
				(type default)
			)
			(layer "F.Fab")
		)
		(fp_line
			(start -0.12065 -0.2794)
			(end 0.12065 -0.2794)
			(stroke
				(width 0.1)
				(type default)
			)
			(layer "F.Fab")
		)
		(fp_line
			(start 0.120396 0.2794)
			(end -0.12065 0.2794)
			(stroke
				(width 0.1)
				(type default)
			)
			(layer "F.Fab")
		)
		(fp_line
			(start -0.12065 0.2794)
			(end -0.12065 0.3048)
			(stroke
				(width 0.1)
				(type default)
			)
			(layer "F.Fab")
		)
		(fp_line
			(start 0.67945 0.3048)
			(end 0.120396 0.3048)
			(stroke
				(width 0.1)
				(type default)
			)
			(layer "F.Fab")
		)
		(fp_line
			(start 0.120396 0.3048)
			(end 0.120396 0.2794)
			(stroke
				(width 0.1)
				(type default)
			)
			(layer "F.Fab")
		)
		(fp_line
			(start -0.12065 0.3048)
			(end -0.67945 0.3048)
			(stroke
				(width 0.1)
				(type default)
			)
			(layer "F.Fab")
		)
		(fp_line
			(start -0.67945 0.3048)
			(end -0.67945 -0.305054)
			(stroke
				(width 0.1)
				(type default)
			)
			(layer "F.Fab")
		)
		(pad "1" smd circle
			(at -0.40005 0 90)
			(size 0 0)
			(layers "F.Cu" "F.Mask" "F.Paste")
			(net "P3V3_AUX")
		)
		(pad "2" smd circle
			(at 0.40005 0 90)
			(size 0 0)
			(layers "F.Cu" "F.Mask" "F.Paste")
			(net "P3V3_P1V8_SD2VDD")
		)
	)
)
